(kicad_pcb
	(version 20260206)
	(generator "pcbnew")
	(generator_version "10.0")
	(general
		(thickness 1.6)
		(legacy_teardrops no)
	)
	(paper "A4")
	(title_block
		(title "04192023_DAF0TMB3IC0_F0TG_MB_C_brd_V02_OCP.brd")
		(comment 1 "Grand Teton / footprint 4761 of 8354 (J18), pads 114-226 of 291")
	)
	(layers
		(0 "F.Cu" signal "TOP")
		(4 "In1.Cu" signal "GND")
		(6 "In2.Cu" signal "IN1")
		(8 "In3.Cu" signal "GND1")
		(10 "In4.Cu" signal "IN2")
		(12 "In5.Cu" signal "GND2")
		(14 "In6.Cu" signal "IN3")
		(16 "In7.Cu" signal "GND3")
		(18 "In8.Cu" signal "VCC")
		(20 "In9.Cu" signal "VCC1")
		(22 "In10.Cu" signal "GND4")
		(24 "In11.Cu" signal "IN4")
		(26 "In12.Cu" signal "GND5")
		(28 "In13.Cu" signal "IN5")
		(30 "In14.Cu" signal "GND6")
		(32 "In15.Cu" signal "IN6")
		(34 "In16.Cu" signal "GND7")
		(2 "B.Cu" signal "BOTTOM")
		(9 "F.Adhes" user "F.Adhesive")
		(11 "B.Adhes" user "B.Adhesive")
		(13 "F.Paste" user "Package Geometry/Pastemask Top")
		(15 "B.Paste" user "Package Geometry/Pastemask Bottom")
		(5 "F.SilkS" user "Ref Des/Silkscreen Top")
		(7 "B.SilkS" user "Ref Des/Silkscreen Bottom")
		(1 "F.Mask" user "Board Geometry/Soldermask Top")
		(3 "B.Mask" user "Board Geometry/Soldermask Bottom")
		(17 "Dwgs.User" user "User.Drawings")
		(19 "Cmts.User" user "User.Comments")
		(21 "Eco1.User" user "User.Eco1")
		(23 "Eco2.User" user "User.Eco2")
		(25 "Edge.Cuts" user "Board Geometry/Outline")
		(27 "Margin" user)
		(31 "F.CrtYd" user "Package Geometry/Place Bound Top")
		(29 "B.CrtYd" user "Package Geometry/Place Bound Bottom")
		(35 "F.Fab" user "Ref Des/Assembly Top")
		(33 "B.Fab" user "Ref Des/Assembly Bottom")
	)
	(footprint ""
		(layer "F.Cu")
		(at 429.506126 -255.560068 180)
		(property "Reference" "J18"
			(at 0.484632 -81.752948 0)
			(unlocked yes)
			(layer "F.SilkS")
			(effects
				(font
					(size 0.7874 0.5842)
					(thickness 0.1524)
				)
			)
		)
		(property "Value" ""
			(at 0 0 180)
			(layer "F.Fab")
			(effects
				(font
					(size 1.27 1.27)
				)
			)
		)
		(duplicate_pad_numbers_are_jumpers no)
		(pad "114" smd rect
			(at -2.050034 37.824918 90)
			(size 0.519938 1.4986)
			(layers "F.Cu" "F.Mask" "F.Paste")
			(net "GND")
		)
		(pad "115" smd rect
			(at -2.050034 38.675056 90)
			(size 0.519938 1.4986)
			(layers "F.Cu" "F.Mask" "F.Paste")
			(net "M_I_CPU0_SB_DQS_DP<1>")
		)
		(pad "116" smd rect
			(at -2.050034 39.52494 90)
			(size 0.519938 1.4986)
			(layers "F.Cu" "F.Mask" "F.Paste")
			(net "M_I_CPU0_SB_DQS_DN<1>")
		)
		(pad "117" smd rect
			(at -2.050034 40.375078 90)
			(size 0.519938 1.4986)
			(layers "F.Cu" "F.Mask" "F.Paste")
			(net "GND")
		)
		(pad "118" smd rect
			(at -2.050034 41.224962 90)
			(size 0.519938 1.4986)
			(layers "F.Cu" "F.Mask" "F.Paste")
			(net "M_I_CPU0_SB_DQ<12>")
		)
		(pad "119" smd rect
			(at -2.050034 42.0751 90)
			(size 0.519938 1.4986)
			(layers "F.Cu" "F.Mask" "F.Paste")
			(net "GND")
		)
		(pad "120" smd rect
			(at -2.050034 42.924984 90)
			(size 0.519938 1.4986)
			(layers "F.Cu" "F.Mask" "F.Paste")
			(net "M_I_CPU0_SB_DQ<13>")
		)
		(pad "121" smd rect
			(at -2.050034 43.775122 90)
			(size 0.519938 1.4986)
			(layers "F.Cu" "F.Mask" "F.Paste")
			(net "GND")
		)
		(pad "122" smd rect
			(at -2.050034 44.625006 90)
			(size 0.519938 1.4986)
			(layers "F.Cu" "F.Mask" "F.Paste")
			(net "M_I_CPU0_SB_DQ<16>")
		)
		(pad "123" smd rect
			(at -2.050034 45.47489 90)
			(size 0.519938 1.4986)
			(layers "F.Cu" "F.Mask" "F.Paste")
			(net "GND")
		)
		(pad "124" smd rect
			(at -2.050034 46.325028 90)
			(size 0.519938 1.4986)
			(layers "F.Cu" "F.Mask" "F.Paste")
			(net "M_I_CPU0_SB_DQ<17>")
		)
		(pad "125" smd rect
			(at -2.050034 47.174912 90)
			(size 0.519938 1.4986)
			(layers "F.Cu" "F.Mask" "F.Paste")
			(net "GND")
		)
		(pad "126" smd rect
			(at -2.050034 48.02505 90)
			(size 0.519938 1.4986)
			(layers "F.Cu" "F.Mask" "F.Paste")
			(net "M_I_CPU0_SB_DQS_DP<2>")
		)
		(pad "127" smd rect
			(at -2.050034 48.874934 90)
			(size 0.519938 1.4986)
			(layers "F.Cu" "F.Mask" "F.Paste")
			(net "M_I_CPU0_SB_DQS_DN<2>")
		)
		(pad "128" smd rect
			(at -2.050034 49.725072 90)
			(size 0.519938 1.4986)
			(layers "F.Cu" "F.Mask" "F.Paste")
			(net "GND")
		)
		(pad "129" smd rect
			(at -2.050034 50.574956 90)
			(size 0.519938 1.4986)
			(layers "F.Cu" "F.Mask" "F.Paste")
			(net "M_I_CPU0_SB_DQ<20>")
		)
		(pad "130" smd rect
			(at -2.050034 51.425094 90)
			(size 0.519938 1.4986)
			(layers "F.Cu" "F.Mask" "F.Paste")
			(net "GND")
		)
		(pad "131" smd rect
			(at -2.050034 52.274978 90)
			(size 0.519938 1.4986)
			(layers "F.Cu" "F.Mask" "F.Paste")
			(net "M_I_CPU0_SB_DQ<21>")
		)
		(pad "132" smd rect
			(at -2.050034 53.125116 90)
			(size 0.519938 1.4986)
			(layers "F.Cu" "F.Mask" "F.Paste")
			(net "GND")
		)
		(pad "133" smd rect
			(at -2.050034 53.975 90)
			(size 0.519938 1.4986)
			(layers "F.Cu" "F.Mask" "F.Paste")
			(net "M_I_CPU0_SB_DQ<24>")
		)
		(pad "134" smd rect
			(at -2.050034 54.824884 90)
			(size 0.519938 1.4986)
			(layers "F.Cu" "F.Mask" "F.Paste")
			(net "GND")
		)
		(pad "135" smd rect
			(at -2.050034 55.675022 90)
			(size 0.519938 1.4986)
			(layers "F.Cu" "F.Mask" "F.Paste")
			(net "M_I_CPU0_SB_DQ<25>")
		)
		(pad "136" smd rect
			(at -2.050034 56.524906 90)
			(size 0.519938 1.4986)
			(layers "F.Cu" "F.Mask" "F.Paste")
			(net "GND")
		)
		(pad "137" smd rect
			(at -2.050034 57.375044 90)
			(size 0.519938 1.4986)
			(layers "F.Cu" "F.Mask" "F.Paste")
			(net "M_I_CPU0_SB_DQS_DP<3>")
		)
		(pad "138" smd rect
			(at -2.050034 58.224928 90)
			(size 0.519938 1.4986)
			(layers "F.Cu" "F.Mask" "F.Paste")
			(net "M_I_CPU0_SB_DQS_DN<3>")
		)
		(pad "139" smd rect
			(at -2.050034 59.075066 90)
			(size 0.519938 1.4986)
			(layers "F.Cu" "F.Mask" "F.Paste")
			(net "GND")
		)
		(pad "140" smd rect
			(at -2.050034 59.92495 90)
			(size 0.519938 1.4986)
			(layers "F.Cu" "F.Mask" "F.Paste")
			(net "M_I_CPU0_SB_DQ<28>")
		)
		(pad "141" smd rect
			(at -2.050034 60.775088 90)
			(size 0.519938 1.4986)
			(layers "F.Cu" "F.Mask" "F.Paste")
			(net "GND")
		)
		(pad "142" smd rect
			(at -2.050034 61.624972 90)
			(size 0.519938 1.4986)
			(layers "F.Cu" "F.Mask" "F.Paste")
			(net "M_I_CPU0_SB_DQ<29>")
		)
		(pad "143" smd rect
			(at -2.050034 62.47511 90)
			(size 0.519938 1.4986)
			(layers "F.Cu" "F.Mask" "F.Paste")
			(net "GND")
		)
		(pad "144" smd rect
			(at -2.050034 63.324994 90)
			(size 0.519938 1.4986)
			(layers "F.Cu" "F.Mask" "F.Paste")
			(net "Net_2362")
		)
		(pad "145" smd rect
			(at 2.050034 -63.324994 90)
			(size 0.519938 1.4986)
			(layers "F.Cu" "F.Mask" "F.Paste")
			(net "P12V_MEM_CPU0")
		)
		(pad "146" smd rect
			(at 2.050034 -62.47511 90)
			(size 0.519938 1.4986)
			(layers "F.Cu" "F.Mask" "F.Paste")
			(net "P12V_MEM_CPU0")
		)
		(pad "147" smd rect
			(at 2.050034 -61.624972 90)
			(size 0.519938 1.4986)
			(layers "F.Cu" "F.Mask" "F.Paste")
			(net "PWRGD_CHI_CPU0_DIMM")
		)
		(pad "148" smd rect
			(at 2.050034 -60.775088 90)
			(size 0.519938 1.4986)
			(layers "F.Cu" "F.Mask" "F.Paste")
			(net "PD_CHI_CPU0_DIMM_SAA")
		)
		(pad "149" smd rect
			(at 2.050034 -59.92495 90)
			(size 0.519938 1.4986)
			(layers "F.Cu" "F.Mask" "F.Paste")
			(net "Net_2363")
		)
		(pad "150" smd rect
			(at 2.050034 -59.075066 90)
			(size 0.519938 1.4986)
			(layers "F.Cu" "F.Mask" "F.Paste")
			(net "Net_2364")
		)
		(pad "151" smd rect
			(at 2.050034 -58.224928 90)
			(size 0.519938 1.4986)
			(layers "F.Cu" "F.Mask" "F.Paste")
			(net "GND")
		)
		(pad "152" smd rect
			(at 2.050034 -57.375044 90)
			(size 0.519938 1.4986)
			(layers "F.Cu" "F.Mask" "F.Paste")
			(net "M_I_CPU0_SA_DQ<2>")
		)
		(pad "153" smd rect
			(at 2.050034 -56.524906 90)
			(size 0.519938 1.4986)
			(layers "F.Cu" "F.Mask" "F.Paste")
			(net "GND")
		)
		(pad "154" smd rect
			(at 2.050034 -55.675022 90)
			(size 0.519938 1.4986)
			(layers "F.Cu" "F.Mask" "F.Paste")
			(net "M_I_CPU0_SA_DQ<3>")
		)
		(pad "155" smd rect
			(at 2.050034 -54.824884 90)
			(size 0.519938 1.4986)
			(layers "F.Cu" "F.Mask" "F.Paste")
			(net "GND")
		)
		(pad "156" smd rect
			(at 2.050034 -53.975 90)
			(size 0.519938 1.4986)
			(layers "F.Cu" "F.Mask" "F.Paste")
			(net "M_I_CPU0_SA_DQS_DN<5>")
		)
		(pad "157" smd rect
			(at 2.050034 -53.125116 90)
			(size 0.519938 1.4986)
			(layers "F.Cu" "F.Mask" "F.Paste")
			(net "M_I_CPU0_SA_DQS_DP<5>")
		)
		(pad "158" smd rect
			(at 2.050034 -52.274978 90)
			(size 0.519938 1.4986)
			(layers "F.Cu" "F.Mask" "F.Paste")
			(net "GND")
		)
		(pad "159" smd rect
			(at 2.050034 -51.425094 90)
			(size 0.519938 1.4986)
			(layers "F.Cu" "F.Mask" "F.Paste")
			(net "M_I_CPU0_SA_DQ<6>")
		)
		(pad "160" smd rect
			(at 2.050034 -50.574956 90)
			(size 0.519938 1.4986)
			(layers "F.Cu" "F.Mask" "F.Paste")
			(net "GND")
		)
		(pad "161" smd rect
			(at 2.050034 -49.725072 90)
			(size 0.519938 1.4986)
			(layers "F.Cu" "F.Mask" "F.Paste")
			(net "M_I_CPU0_SA_DQ<7>")
		)
		(pad "162" smd rect
			(at 2.050034 -48.874934 90)
			(size 0.519938 1.4986)
			(layers "F.Cu" "F.Mask" "F.Paste")
			(net "GND")
		)
		(pad "163" smd rect
			(at 2.050034 -48.02505 90)
			(size 0.519938 1.4986)
			(layers "F.Cu" "F.Mask" "F.Paste")
			(net "M_I_CPU0_SA_DQ<10>")
		)
		(pad "164" smd rect
			(at 2.050034 -47.174912 90)
			(size 0.519938 1.4986)
			(layers "F.Cu" "F.Mask" "F.Paste")
			(net "GND")
		)
		(pad "165" smd rect
			(at 2.050034 -46.325028 90)
			(size 0.519938 1.4986)
			(layers "F.Cu" "F.Mask" "F.Paste")
			(net "M_I_CPU0_SA_DQ<11>")
		)
		(pad "166" smd rect
			(at 2.050034 -45.47489 90)
			(size 0.519938 1.4986)
			(layers "F.Cu" "F.Mask" "F.Paste")
			(net "GND")
		)
		(pad "167" smd rect
			(at 2.050034 -44.625006 90)
			(size 0.519938 1.4986)
			(layers "F.Cu" "F.Mask" "F.Paste")
			(net "M_I_CPU0_SA_DQS_DN<6>")
		)
		(pad "168" smd rect
			(at 2.050034 -43.775122 90)
			(size 0.519938 1.4986)
			(layers "F.Cu" "F.Mask" "F.Paste")
			(net "M_I_CPU0_SA_DQS_DP<6>")
		)
		(pad "169" smd rect
			(at 2.050034 -42.924984 90)
			(size 0.519938 1.4986)
			(layers "F.Cu" "F.Mask" "F.Paste")
			(net "GND")
		)
		(pad "170" smd rect
			(at 2.050034 -42.0751 90)
			(size 0.519938 1.4986)
			(layers "F.Cu" "F.Mask" "F.Paste")
			(net "M_I_CPU0_SA_DQ<14>")
		)
		(pad "171" smd rect
			(at 2.050034 -41.224962 90)
			(size 0.519938 1.4986)
			(layers "F.Cu" "F.Mask" "F.Paste")
			(net "GND")
		)
		(pad "172" smd rect
			(at 2.050034 -40.375078 90)
			(size 0.519938 1.4986)
			(layers "F.Cu" "F.Mask" "F.Paste")
			(net "M_I_CPU0_SA_DQ<15>")
		)
		(pad "173" smd rect
			(at 2.050034 -39.52494 90)
			(size 0.519938 1.4986)
			(layers "F.Cu" "F.Mask" "F.Paste")
			(net "GND")
		)
		(pad "174" smd rect
			(at 2.050034 -38.675056 90)
			(size 0.519938 1.4986)
			(layers "F.Cu" "F.Mask" "F.Paste")
			(net "M_I_CPU0_SA_DQ<18>")
		)
		(pad "175" smd rect
			(at 2.050034 -37.824918 90)
			(size 0.519938 1.4986)
			(layers "F.Cu" "F.Mask" "F.Paste")
			(net "GND")
		)
		(pad "176" smd rect
			(at 2.050034 -36.975034 90)
			(size 0.519938 1.4986)
			(layers "F.Cu" "F.Mask" "F.Paste")
			(net "M_I_CPU0_SA_DQ<19>")
		)
		(pad "177" smd rect
			(at 2.050034 -36.124896 90)
			(size 0.519938 1.4986)
			(layers "F.Cu" "F.Mask" "F.Paste")
			(net "GND")
		)
		(pad "178" smd rect
			(at 2.050034 -35.275012 90)
			(size 0.519938 1.4986)
			(layers "F.Cu" "F.Mask" "F.Paste")
			(net "M_I_CPU0_SA_DQS_DN<7>")
		)
		(pad "179" smd rect
			(at 2.050034 -34.425128 90)
			(size 0.519938 1.4986)
			(layers "F.Cu" "F.Mask" "F.Paste")
			(net "M_I_CPU0_SA_DQS_DP<7>")
		)
		(pad "180" smd rect
			(at 2.050034 -33.57499 90)
			(size 0.519938 1.4986)
			(layers "F.Cu" "F.Mask" "F.Paste")
			(net "GND")
		)
		(pad "181" smd rect
			(at 2.050034 -32.725106 90)
			(size 0.519938 1.4986)
			(layers "F.Cu" "F.Mask" "F.Paste")
			(net "M_I_CPU0_SA_DQ<22>")
		)
		(pad "182" smd rect
			(at 2.050034 -31.874968 90)
			(size 0.519938 1.4986)
			(layers "F.Cu" "F.Mask" "F.Paste")
			(net "GND")
		)
		(pad "183" smd rect
			(at 2.050034 -31.025084 90)
			(size 0.519938 1.4986)
			(layers "F.Cu" "F.Mask" "F.Paste")
			(net "M_I_CPU0_SA_DQ<23>")
		)
		(pad "184" smd rect
			(at 2.050034 -30.174946 90)
			(size 0.519938 1.4986)
			(layers "F.Cu" "F.Mask" "F.Paste")
			(net "GND")
		)
		(pad "185" smd rect
			(at 2.050034 -29.325062 90)
			(size 0.519938 1.4986)
			(layers "F.Cu" "F.Mask" "F.Paste")
			(net "M_I_CPU0_SA_DQ<26>")
		)
		(pad "186" smd rect
			(at 2.050034 -28.474924 90)
			(size 0.519938 1.4986)
			(layers "F.Cu" "F.Mask" "F.Paste")
			(net "GND")
		)
		(pad "187" smd rect
			(at 2.050034 -27.62504 90)
			(size 0.519938 1.4986)
			(layers "F.Cu" "F.Mask" "F.Paste")
			(net "M_I_CPU0_SA_DQ<27>")
		)
		(pad "188" smd rect
			(at 2.050034 -26.774902 90)
			(size 0.519938 1.4986)
			(layers "F.Cu" "F.Mask" "F.Paste")
			(net "GND")
		)
		(pad "189" smd rect
			(at 2.050034 -25.925018 90)
			(size 0.519938 1.4986)
			(layers "F.Cu" "F.Mask" "F.Paste")
			(net "M_I_CPU0_SA_DQS_DN<8>")
		)
		(pad "190" smd rect
			(at 2.050034 -25.07488 90)
			(size 0.519938 1.4986)
			(layers "F.Cu" "F.Mask" "F.Paste")
			(net "M_I_CPU0_SA_DQS_DP<8>")
		)
		(pad "191" smd rect
			(at 2.050034 -24.224996 90)
			(size 0.519938 1.4986)
			(layers "F.Cu" "F.Mask" "F.Paste")
			(net "GND")
		)
		(pad "192" smd rect
			(at 2.050034 -23.375112 90)
			(size 0.519938 1.4986)
			(layers "F.Cu" "F.Mask" "F.Paste")
			(net "M_I_CPU0_SA_DQ<30>")
		)
		(pad "193" smd rect
			(at 2.050034 -22.524974 90)
			(size 0.519938 1.4986)
			(layers "F.Cu" "F.Mask" "F.Paste")
			(net "GND")
		)
		(pad "194" smd rect
			(at 2.050034 -21.67509 90)
			(size 0.519938 1.4986)
			(layers "F.Cu" "F.Mask" "F.Paste")
			(net "M_I_CPU0_SA_DQ<31>")
		)
		(pad "195" smd rect
			(at 2.050034 -20.824952 90)
			(size 0.519938 1.4986)
			(layers "F.Cu" "F.Mask" "F.Paste")
			(net "GND")
		)
		(pad "196" smd rect
			(at 2.050034 -19.975068 90)
			(size 0.519938 1.4986)
			(layers "F.Cu" "F.Mask" "F.Paste")
			(net "M_I_CPU0_SA_CB<2>")
		)
		(pad "197" smd rect
			(at 2.050034 -19.12493 90)
			(size 0.519938 1.4986)
			(layers "F.Cu" "F.Mask" "F.Paste")
			(net "GND")
		)
		(pad "198" smd rect
			(at 2.050034 -18.275046 90)
			(size 0.519938 1.4986)
			(layers "F.Cu" "F.Mask" "F.Paste")
			(net "M_I_CPU0_SA_CB<3>")
		)
		(pad "199" smd rect
			(at 2.050034 -17.424908 90)
			(size 0.519938 1.4986)
			(layers "F.Cu" "F.Mask" "F.Paste")
			(net "GND")
		)
		(pad "200" smd rect
			(at 2.050034 -16.575024 90)
			(size 0.519938 1.4986)
			(layers "F.Cu" "F.Mask" "F.Paste")
			(net "M_I_CPU0_SA_DQS_DN<9>")
		)
		(pad "201" smd rect
			(at 2.050034 -15.724886 90)
			(size 0.519938 1.4986)
			(layers "F.Cu" "F.Mask" "F.Paste")
			(net "M_I_CPU0_SA_DQS_DP<9>")
		)
		(pad "202" smd rect
			(at 2.050034 -14.875002 90)
			(size 0.519938 1.4986)
			(layers "F.Cu" "F.Mask" "F.Paste")
			(net "GND")
		)
		(pad "203" smd rect
			(at 2.050034 -14.025118 90)
			(size 0.519938 1.4986)
			(layers "F.Cu" "F.Mask" "F.Paste")
			(net "M_I_CPU0_SA_CB<6>")
		)
		(pad "204" smd rect
			(at 2.050034 -13.17498 90)
			(size 0.519938 1.4986)
			(layers "F.Cu" "F.Mask" "F.Paste")
			(net "GND")
		)
		(pad "205" smd rect
			(at 2.050034 -12.325096 90)
			(size 0.519938 1.4986)
			(layers "F.Cu" "F.Mask" "F.Paste")
			(net "M_I_CPU0_SA_CB<7>")
		)
		(pad "206" smd rect
			(at 2.050034 -11.474958 90)
			(size 0.519938 1.4986)
			(layers "F.Cu" "F.Mask" "F.Paste")
			(net "GND")
		)
		(pad "207" smd rect
			(at 2.050034 -10.625074 90)
			(size 0.519938 1.4986)
			(layers "F.Cu" "F.Mask" "F.Paste")
			(net "M_I_CPU0_RESET_N")
		)
		(pad "208" smd rect
			(at 2.050034 -9.774936 90)
			(size 0.519938 1.4986)
			(layers "F.Cu" "F.Mask" "F.Paste")
			(net "GND")
		)
		(pad "209" smd rect
			(at 2.050034 -8.925052 90)
			(size 0.519938 1.4986)
			(layers "F.Cu" "F.Mask" "F.Paste")
			(net "M_I_CPU0_SA_CS_N<1>")
		)
		(pad "210" smd rect
			(at 2.050034 -8.074914 90)
			(size 0.519938 1.4986)
			(layers "F.Cu" "F.Mask" "F.Paste")
			(net "GND")
		)
		(pad "211" smd rect
			(at 2.050034 -7.22503 90)
			(size 0.519938 1.4986)
			(layers "F.Cu" "F.Mask" "F.Paste")
			(net "M_I_CPU0_SA_CA<1>")
		)
		(pad "212" smd rect
			(at 2.050034 -6.374892 90)
			(size 0.519938 1.4986)
			(layers "F.Cu" "F.Mask" "F.Paste")
			(net "GND")
		)
		(pad "213" smd rect
			(at 2.050034 -5.525008 90)
			(size 0.519938 1.4986)
			(layers "F.Cu" "F.Mask" "F.Paste")
			(net "M_I_CPU0_SA_CA<3>")
		)
		(pad "214" smd rect
			(at 2.050034 -4.675124 90)
			(size 0.519938 1.4986)
			(layers "F.Cu" "F.Mask" "F.Paste")
			(net "GND")
		)
		(pad "215" smd rect
			(at 2.050034 -3.824986 90)
			(size 0.519938 1.4986)
			(layers "F.Cu" "F.Mask" "F.Paste")
			(net "M_I_CPU0_SA_CA<5>")
		)
		(pad "216" smd rect
			(at 2.050034 -2.975102 90)
			(size 0.519938 1.4986)
			(layers "F.Cu" "F.Mask" "F.Paste")
			(net "GND")
		)
		(pad "217" smd rect
			(at 2.050034 -2.124964 90)
			(size 0.519938 1.4986)
			(layers "F.Cu" "F.Mask" "F.Paste")
			(net "M_I_CPU0_CLK_DP<0>")
		)
		(pad "218" smd rect
			(at 2.050034 -1.27508 90)
			(size 0.519938 1.4986)
			(layers "F.Cu" "F.Mask" "F.Paste")
			(net "M_I_CPU0_CLK_DN<0>")
		)
		(pad "219" smd rect
			(at 2.050034 -0.424942 90)
			(size 0.519938 1.4986)
			(layers "F.Cu" "F.Mask" "F.Paste")
			(net "GND")
		)
		(pad "220" smd rect
			(at 2.050034 5.525008 90)
			(size 0.519938 1.4986)
			(layers "F.Cu" "F.Mask" "F.Paste")
			(net "Net_2365")
		)
		(pad "221" smd rect
			(at 2.050034 6.374892 90)
			(size 0.519938 1.4986)
			(layers "F.Cu" "F.Mask" "F.Paste")
			(net "M_I_CPU0_SB_CA<1>")
		)
		(pad "222" smd rect
			(at 2.050034 7.22503 90)
			(size 0.519938 1.4986)
			(layers "F.Cu" "F.Mask" "F.Paste")
			(net "GND")
		)
		(pad "223" smd rect
			(at 2.050034 8.074914 90)
			(size 0.519938 1.4986)
			(layers "F.Cu" "F.Mask" "F.Paste")
			(net "M_I_CPU0_SB_CA<3>")
		)
		(pad "224" smd rect
			(at 2.050034 8.925052 90)
			(size 0.519938 1.4986)
			(layers "F.Cu" "F.Mask" "F.Paste")
			(net "GND")
		)
		(pad "225" smd rect
			(at 2.050034 9.774936 90)
			(size 0.519938 1.4986)
			(layers "F.Cu" "F.Mask" "F.Paste")
			(net "M_I_CPU0_SB_CA<5>")
		)
		(pad "226" smd rect
			(at 2.050034 10.625074 90)
			(size 0.519938 1.4986)
			(layers "F.Cu" "F.Mask" "F.Paste")
			(net "GND")
		)
	)
)
